(kicad_pcb
	(version 20260206)
	(generator "pcbnew")
	(generator_version "10.0")
	(general
		(thickness 1.6)
		(legacy_teardrops no)
	)
	(paper "A4")
	(title_block
		(title "03242023_DA0F0TMBIJ0_F0T_Motherboard_J_brd_V01_OCP.brd")
		(comment 1 "Grand Teton / footprints 5401-5406 of 6105")
	)
	(layers
		(0 "F.Cu" signal "TOP")
		(4 "In1.Cu" signal "GND")
		(6 "In2.Cu" signal "IN1")
		(8 "In3.Cu" signal "GND1")
		(10 "In4.Cu" signal "IN2")
		(12 "In5.Cu" signal "GND2")
		(14 "In6.Cu" signal "IN3")
		(16 "In7.Cu" signal "GND3")
		(18 "In8.Cu" signal "VCC")
		(20 "In9.Cu" signal "VCC1")
		(22 "In10.Cu" signal "GND4")
		(24 "In11.Cu" signal "IN4")
		(26 "In12.Cu" signal "GND5")
		(28 "In13.Cu" signal "IN5")
		(30 "In14.Cu" signal "GND6")
		(32 "In15.Cu" signal "IN6")
		(34 "In16.Cu" signal "GND7")
		(2 "B.Cu" signal "BOTTOM")
		(9 "F.Adhes" user "F.Adhesive")
		(11 "B.Adhes" user "B.Adhesive")
		(13 "F.Paste" user "Package Geometry/Pastemask Top")
		(15 "B.Paste" user "Package Geometry/Pastemask Bottom")
		(5 "F.SilkS" user "Ref Des/Silkscreen Top")
		(7 "B.SilkS" user "Ref Des/Silkscreen Bottom")
		(1 "F.Mask" user "Board Geometry/Soldermask Top")
		(3 "B.Mask" user "Board Geometry/Soldermask Bottom")
		(17 "Dwgs.User" user "User.Drawings")
		(19 "Cmts.User" user "User.Comments")
		(21 "Eco1.User" user "User.Eco1")
		(23 "Eco2.User" user "User.Eco2")
		(25 "Edge.Cuts" user "Board Geometry/Outline")
		(27 "Margin" user)
		(31 "F.CrtYd" user "Package Geometry/Place Bound Top")
		(29 "B.CrtYd" user "Package Geometry/Place Bound Bottom")
		(35 "F.Fab" user "Ref Des/Assembly Top")
		(33 "B.Fab" user "Ref Des/Assembly Bottom")
	)
	(footprint ""
		(layer "B.Cu")
		(at 174.393352 -22.564598 -90)
		(property "Reference" "R1764"
			(at 0 0 90)
			(layer "B.SilkS")
			(hide yes)
			(effects
				(font
					(size 1.27 1.27)
				)
				(justify mirror)
			)
		)
		(property "Value" ""
			(at 0 0 90)
			(layer "B.Fab")
			(effects
				(font
					(size 1.27 1.27)
				)
				(justify mirror)
			)
		)
		(duplicate_pad_numbers_are_jumpers no)
		(fp_line
			(start -0.7874 0.4064)
			(end 0.7874 0.4064)
			(stroke
				(width 0.1524)
				(type default)
			)
			(layer "B.SilkS")
		)
		(fp_line
			(start 0.7874 0.4064)
			(end 0.7874 -0.4064)
			(stroke
				(width 0.1524)
				(type default)
			)
			(layer "B.SilkS")
		)
		(fp_line
			(start -0.7874 -0.4064)
			(end -0.7874 0.4064)
			(stroke
				(width 0.1524)
				(type default)
			)
			(layer "B.SilkS")
		)
		(fp_line
			(start 0.7874 -0.4064)
			(end -0.7874 -0.4064)
			(stroke
				(width 0.1524)
				(type default)
			)
			(layer "B.SilkS")
		)
		(fp_line
			(start -0.67945 0.3048)
			(end -0.120396 0.3048)
			(stroke
				(width 0.1)
				(type default)
			)
			(layer "B.Fab")
		)
		(fp_line
			(start -0.120396 0.3048)
			(end -0.120396 0.2794)
			(stroke
				(width 0.1)
				(type default)
			)
			(layer "B.Fab")
		)
		(fp_line
			(start 0.12065 0.3048)
			(end 0.67945 0.3048)
			(stroke
				(width 0.1)
				(type default)
			)
			(layer "B.Fab")
		)
		(fp_line
			(start 0.67945 0.3048)
			(end 0.67945 -0.305054)
			(stroke
				(width 0.1)
				(type default)
			)
			(layer "B.Fab")
		)
		(fp_line
			(start -0.120396 0.2794)
			(end 0.12065 0.2794)
			(stroke
				(width 0.1)
				(type default)
			)
			(layer "B.Fab")
		)
		(fp_line
			(start 0.12065 0.2794)
			(end 0.12065 0.3048)
			(stroke
				(width 0.1)
				(type default)
			)
			(layer "B.Fab")
		)
		(fp_line
			(start -0.12065 -0.2794)
			(end -0.12065 -0.3048)
			(stroke
				(width 0.1)
				(type default)
			)
			(layer "B.Fab")
		)
		(fp_line
			(start 0.12065 -0.2794)
			(end -0.12065 -0.2794)
			(stroke
				(width 0.1)
				(type default)
			)
			(layer "B.Fab")
		)
		(fp_line
			(start -0.67945 -0.3048)
			(end -0.67945 0.3048)
			(stroke
				(width 0.1)
				(type default)
			)
			(layer "B.Fab")
		)
		(fp_line
			(start -0.12065 -0.3048)
			(end -0.67945 -0.3048)
			(stroke
				(width 0.1)
				(type default)
			)
			(layer "B.Fab")
		)
		(fp_line
			(start 0.12065 -0.305054)
			(end 0.12065 -0.2794)
			(stroke
				(width 0.1)
				(type default)
			)
			(layer "B.Fab")
		)
		(fp_line
			(start 0.67945 -0.305054)
			(end 0.12065 -0.305054)
			(stroke
				(width 0.1)
				(type default)
			)
			(layer "B.Fab")
		)
		(pad "1" smd circle
			(at 0.40005 0 90)
			(size 0 0)
			(layers "B.Cu" "B.Mask" "B.Paste")
			(net "FM_LPC_ESPI_SEL")
		)
		(pad "2" smd circle
			(at -0.40005 0 90)
			(size 0 0)
			(layers "B.Cu" "B.Mask" "B.Paste")
			(net "GND")
		)
	)
	(footprint ""
		(layer "B.Cu")
		(at 188.309758 -13.60043 -90)
		(property "Reference" "R595"
			(at 0 0 90)
			(layer "B.SilkS")
			(hide yes)
			(effects
				(font
					(size 1.27 1.27)
				)
				(justify mirror)
			)
		)
		(property "Value" ""
			(at 0 0 90)
			(layer "B.Fab")
			(effects
				(font
					(size 1.27 1.27)
				)
				(justify mirror)
			)
		)
		(duplicate_pad_numbers_are_jumpers no)
		(fp_line
			(start -0.7874 0.4064)
			(end 0.7874 0.4064)
			(stroke
				(width 0.1524)
				(type default)
			)
			(layer "B.SilkS")
		)
		(fp_line
			(start 0.7874 0.4064)
			(end 0.7874 -0.4064)
			(stroke
				(width 0.1524)
				(type default)
			)
			(layer "B.SilkS")
		)
		(fp_line
			(start -0.7874 -0.4064)
			(end -0.7874 0.4064)
			(stroke
				(width 0.1524)
				(type default)
			)
			(layer "B.SilkS")
		)
		(fp_line
			(start 0.7874 -0.4064)
			(end -0.7874 -0.4064)
			(stroke
				(width 0.1524)
				(type default)
			)
			(layer "B.SilkS")
		)
		(fp_line
			(start -0.67945 0.3048)
			(end -0.120396 0.3048)
			(stroke
				(width 0.1)
				(type default)
			)
			(layer "B.Fab")
		)
		(fp_line
			(start -0.120396 0.3048)
			(end -0.120396 0.2794)
			(stroke
				(width 0.1)
				(type default)
			)
			(layer "B.Fab")
		)
		(fp_line
			(start 0.12065 0.3048)
			(end 0.67945 0.3048)
			(stroke
				(width 0.1)
				(type default)
			)
			(layer "B.Fab")
		)
		(fp_line
			(start 0.67945 0.3048)
			(end 0.67945 -0.305054)
			(stroke
				(width 0.1)
				(type default)
			)
			(layer "B.Fab")
		)
		(fp_line
			(start -0.120396 0.2794)
			(end 0.12065 0.2794)
			(stroke
				(width 0.1)
				(type default)
			)
			(layer "B.Fab")
		)
		(fp_line
			(start 0.12065 0.2794)
			(end 0.12065 0.3048)
			(stroke
				(width 0.1)
				(type default)
			)
			(layer "B.Fab")
		)
		(fp_line
			(start -0.12065 -0.2794)
			(end -0.12065 -0.3048)
			(stroke
				(width 0.1)
				(type default)
			)
			(layer "B.Fab")
		)
		(fp_line
			(start 0.12065 -0.2794)
			(end -0.12065 -0.2794)
			(stroke
				(width 0.1)
				(type default)
			)
			(layer "B.Fab")
		)
		(fp_line
			(start -0.67945 -0.3048)
			(end -0.67945 0.3048)
			(stroke
				(width 0.1)
				(type default)
			)
			(layer "B.Fab")
		)
		(fp_line
			(start -0.12065 -0.3048)
			(end -0.67945 -0.3048)
			(stroke
				(width 0.1)
				(type default)
			)
			(layer "B.Fab")
		)
		(fp_line
			(start 0.12065 -0.305054)
			(end 0.12065 -0.2794)
			(stroke
				(width 0.1)
				(type default)
			)
			(layer "B.Fab")
		)
		(fp_line
			(start 0.67945 -0.305054)
			(end 0.12065 -0.305054)
			(stroke
				(width 0.1)
				(type default)
			)
			(layer "B.Fab")
		)
		(pad "1" smd circle
			(at 0.40005 0 90)
			(size 0 0)
			(layers "B.Cu" "B.Mask" "B.Paste")
			(net "I3C_SPD_DDREFGH_CPU0_BMC_R_SCL")
		)
		(pad "2" smd circle
			(at -0.40005 0 90)
			(size 0 0)
			(layers "B.Cu" "B.Mask" "B.Paste")
			(net "I3C_SPD_DDREFGH_CPU0_BMC_SCL")
		)
	)
	(footprint ""
		(layer "B.Cu")
		(at 429.105568 -362.107226 90)
		(property "Reference" "PC1179_P0_3"
			(at 0 0 90)
			(layer "B.SilkS")
			(hide yes)
			(effects
				(font
					(size 1.27 1.27)
				)
				(justify mirror)
			)
		)
		(property "Value" ""
			(at 0 0 90)
			(layer "B.Fab")
			(effects
				(font
					(size 1.27 1.27)
				)
				(justify mirror)
			)
		)
		(duplicate_pad_numbers_are_jumpers no)
		(fp_line
			(start 1.524 -0.762)
			(end -1.524 -0.762)
			(stroke
				(width 0.1524)
				(type default)
			)
			(layer "B.SilkS")
		)
		(fp_line
			(start -1.524 -0.762)
			(end -1.524 0.762)
			(stroke
				(width 0.1524)
				(type default)
			)
			(layer "B.SilkS")
		)
		(fp_line
			(start 1.524 0.762)
			(end 1.524 -0.762)
			(stroke
				(width 0.1524)
				(type default)
			)
			(layer "B.SilkS")
		)
		(fp_line
			(start -1.524 0.762)
			(end 1.524 0.762)
			(stroke
				(width 0.1524)
				(type default)
			)
			(layer "B.SilkS")
		)
		(fp_line
			(start 1.1049 -0.724916)
			(end 1.1049 0.724916)
			(stroke
				(width 0.1)
				(type default)
			)
			(layer "B.Fab")
		)
		(fp_line
			(start -1.1049 -0.724916)
			(end 1.1049 -0.724916)
			(stroke
				(width 0.1)
				(type default)
			)
			(layer "B.Fab")
		)
		(fp_line
			(start 1.1049 0.724916)
			(end -1.1049 0.724916)
			(stroke
				(width 0.1)
				(type default)
			)
			(layer "B.Fab")
		)
		(fp_line
			(start -1.1049 0.724916)
			(end -1.1049 -0.724916)
			(stroke
				(width 0.1)
				(type default)
			)
			(layer "B.Fab")
		)
		(pad "1" smd rect
			(at 0.889 0 90)
			(size 1.016 1.27)
			(layers "B.Cu" "B.Mask" "B.Paste")
			(net "SW_P12V_PVCCFA_EHV_FIVRA_CPU0_R")
		)
		(pad "2" smd rect
			(at -0.889 0 90)
			(size 1.016 1.27)
			(layers "B.Cu" "B.Mask" "B.Paste")
			(net "GND")
		)
	)
	(footprint ""
		(layer "B.Cu")
		(at 176.3776 -13.762228 90)
		(property "Reference" "R2424"
			(at 0 0 90)
			(layer "B.SilkS")
			(hide yes)
			(effects
				(font
					(size 1.27 1.27)
				)
				(justify mirror)
			)
		)
		(property "Value" ""
			(at 0 0 90)
			(layer "B.Fab")
			(effects
				(font
					(size 1.27 1.27)
				)
				(justify mirror)
			)
		)
		(duplicate_pad_numbers_are_jumpers no)
		(fp_line
			(start 0.7874 -0.4064)
			(end -0.7874 -0.4064)
			(stroke
				(width 0.1524)
				(type default)
			)
			(layer "B.SilkS")
		)
		(fp_line
			(start -0.7874 -0.4064)
			(end -0.7874 0.4064)
			(stroke
				(width 0.1524)
				(type default)
			)
			(layer "B.SilkS")
		)
		(fp_line
			(start 0.7874 0.4064)
			(end 0.7874 -0.4064)
			(stroke
				(width 0.1524)
				(type default)
			)
			(layer "B.SilkS")
		)
		(fp_line
			(start -0.7874 0.4064)
			(end 0.7874 0.4064)
			(stroke
				(width 0.1524)
				(type default)
			)
			(layer "B.SilkS")
		)
		(fp_line
			(start 0.67945 -0.305054)
			(end 0.12065 -0.305054)
			(stroke
				(width 0.1)
				(type default)
			)
			(layer "B.Fab")
		)
		(fp_line
			(start 0.12065 -0.305054)
			(end 0.12065 -0.2794)
			(stroke
				(width 0.1)
				(type default)
			)
			(layer "B.Fab")
		)
		(fp_line
			(start -0.12065 -0.3048)
			(end -0.67945 -0.3048)
			(stroke
				(width 0.1)
				(type default)
			)
			(layer "B.Fab")
		)
		(fp_line
			(start -0.67945 -0.3048)
			(end -0.67945 0.3048)
			(stroke
				(width 0.1)
				(type default)
			)
			(layer "B.Fab")
		)
		(fp_line
			(start 0.12065 -0.2794)
			(end -0.12065 -0.2794)
			(stroke
				(width 0.1)
				(type default)
			)
			(layer "B.Fab")
		)
		(fp_line
			(start -0.12065 -0.2794)
			(end -0.12065 -0.3048)
			(stroke
				(width 0.1)
				(type default)
			)
			(layer "B.Fab")
		)
		(fp_line
			(start 0.12065 0.2794)
			(end 0.12065 0.3048)
			(stroke
				(width 0.1)
				(type default)
			)
			(layer "B.Fab")
		)
		(fp_line
			(start -0.120396 0.2794)
			(end 0.12065 0.2794)
			(stroke
				(width 0.1)
				(type default)
			)
			(layer "B.Fab")
		)
		(fp_line
			(start 0.67945 0.3048)
			(end 0.67945 -0.305054)
			(stroke
				(width 0.1)
				(type default)
			)
			(layer "B.Fab")
		)
		(fp_line
			(start 0.12065 0.3048)
			(end 0.67945 0.3048)
			(stroke
				(width 0.1)
				(type default)
			)
			(layer "B.Fab")
		)
		(fp_line
			(start -0.120396 0.3048)
			(end -0.120396 0.2794)
			(stroke
				(width 0.1)
				(type default)
			)
			(layer "B.Fab")
		)
		(fp_line
			(start -0.67945 0.3048)
			(end -0.120396 0.3048)
			(stroke
				(width 0.1)
				(type default)
			)
			(layer "B.Fab")
		)
		(pad "1" smd circle
			(at 0.40005 0 270)
			(size 0 0)
			(layers "B.Cu" "B.Mask" "B.Paste")
			(net "SMB_SML1_PMBUS_3V3AUX_PCH_SDA")
		)
		(pad "2" smd circle
			(at -0.40005 0 270)
			(size 0 0)
			(layers "B.Cu" "B.Mask" "B.Paste")
			(net "SMB_SML1_PMBUS_3V3AUX_PCH_SDA_R")
		)
	)
	(footprint ""
		(layer "B.Cu")
		(at 477.30537 -153.123392 90)
		(property "Reference" "X38"
			(at -2.374392 -2.22504 270)
			(unlocked yes)
			(layer "B.SilkS")
			(effects
				(font
					(size 0.7874 0.5842)
					(thickness 0.1524)
				)
				(justify left mirror)
			)
		)
		(property "Value" ""
			(at 0 0 90)
			(layer "B.Fab")
			(effects
				(font
					(size 1.27 1.27)
				)
				(justify mirror)
			)
		)
		(property "Device Type" "TP_TDR_4P_FTS_TH-TP_TDR_4P_DIPA"
			(at -1.30175 1.27 0)
			(unlocked yes)
			(layer "B.Fab")
			(hide yes)
			(effects
				(font
					(size 0.635 0.4064)
					(thickness 0.1524)
				)
				(justify mirror)
			)
		)
		(property "User Part Number" "N_A"
			(at -1.30175 1.27 0)
			(unlocked yes)
			(layer "Cmts.User")
			(hide yes)
			(effects
				(font
					(size 0.635 0.4064)
					(thickness 0.1524)
				)
				(justify mirror)
			)
		)
		(duplicate_pad_numbers_are_jumpers no)
		(fp_line
			(start 0 -1.27)
			(end 0 -0.635)
			(stroke
				(width 0.1524)
				(type default)
			)
			(layer "B.SilkS")
		)
		(fp_line
			(start -2.54 -1.27)
			(end 0 -1.27)
			(stroke
				(width 0.1524)
				(type default)
			)
			(layer "B.SilkS")
		)
		(fp_line
			(start -2.54 -1.1303)
			(end -2.54 -1.27)
			(stroke
				(width 0.1524)
				(type default)
			)
			(layer "B.SilkS")
		)
		(fp_line
			(start 0 0.635)
			(end 0 1.905)
			(stroke
				(width 0.1524)
				(type default)
			)
			(layer "B.SilkS")
		)
		(fp_line
			(start -2.54 1.4097)
			(end -2.54 1.1303)
			(stroke
				(width 0.1524)
				(type default)
			)
			(layer "B.SilkS")
		)
		(fp_line
			(start 0 3.175)
			(end 0 3.81)
			(stroke
				(width 0.1524)
				(type default)
			)
			(layer "B.SilkS")
		)
		(fp_line
			(start 0 3.81)
			(end -2.54 3.81)
			(stroke
				(width 0.1524)
				(type default)
			)
			(layer "B.SilkS")
		)
		(fp_line
			(start -2.54 3.81)
			(end -2.54 3.6703)
			(stroke
				(width 0.1524)
				(type default)
			)
			(layer "B.SilkS")
		)
		(fp_poly
			(pts
				(xy 0.761746 0) (xy 2.285746 -0.762) (xy 2.285746 0.762)
			)
			(stroke
				(width 0)
				(type default)
			)
			(fill yes)
			(layer "B.SilkS")
		)
		(fp_line
			(start 0 -1.27)
			(end 0 3.81)
			(stroke
				(width 0.1)
				(type default)
			)
			(layer "B.Fab")
		)
		(fp_line
			(start -2.54 -1.27)
			(end 0 -1.27)
			(stroke
				(width 0.1)
				(type default)
			)
			(layer "B.Fab")
		)
		(fp_line
			(start 0 3.81)
			(end -2.54 3.81)
			(stroke
				(width 0.1)
				(type default)
			)
			(layer "B.Fab")
		)
		(fp_line
			(start -2.54 3.81)
			(end -2.54 -1.27)
			(stroke
				(width 0.1)
				(type default)
			)
			(layer "B.Fab")
		)
		(fp_poly
			(pts
				(xy 0.761746 0) (xy 2.285746 -0.762) (xy 2.285746 0.762)
			)
			(stroke
				(width 0)
				(type default)
			)
			(fill yes)
			(layer "B.Fab")
		)
		(pad "1" thru_hole circle
			(at 0 0 270)
			(size 1.0033 1.0033)
			(drill 0.249936)
			(layers "*.Cu" "*.Mask")
			(remove_unused_layers no)
			(net "TDR_DIFF_85_NECK_IN5_DP")
			(clearance 0.10795)
			(padstack
				(mode front_inner_back)
				(layer "Inner"
					(shape circle)
					(size 0.8001 0.8001)
					(clearance 0.1524)
				)
				(layer "B.Cu"
					(shape circle)
					(size 1.0033 1.0033)
					(thermal_gap 0.10795)
					(clearance 0.10795)
				)
			)
		)
		(pad "2" thru_hole circle
			(at -2.54 0 270)
			(size 1.9939 1.9939)
			(drill 0.249936)
			(layers "*.Cu" "*.Mask")
			(remove_unused_layers no)
			(net "T1_GND")
			(clearance 0.10795)
			(padstack
				(mode front_inner_back)
				(layer "Inner"
					(shape circle)
					(size 0.8001 0.8001)
					(clearance 0.1524)
				)
				(layer "B.Cu"
					(shape circle)
					(size 1.9939 1.9939)
					(thermal_gap 0.10795)
					(clearance 0.10795)
				)
			)
		)
		(pad "3" thru_hole circle
			(at -2.54 2.54 270)
			(size 1.9939 1.9939)
			(drill 0.249936)
			(layers "*.Cu" "*.Mask")
			(remove_unused_layers no)
			(net "T1_GND")
			(clearance 0.10795)
			(padstack
				(mode front_inner_back)
				(layer "Inner"
					(shape circle)
					(size 0.8001 0.8001)
					(clearance 0.1524)
				)
				(layer "B.Cu"
					(shape circle)
					(size 1.9939 1.9939)
					(thermal_gap 0.10795)
					(clearance 0.10795)
				)
			)
		)
		(pad "4" thru_hole circle
			(at 0 2.54 270)
			(size 1.0033 1.0033)
			(drill 0.249936)
			(layers "*.Cu" "*.Mask")
			(remove_unused_layers no)
			(net "TDR_DIFF_85_NECK_IN5_DN")
			(clearance 0.10795)
			(padstack
				(mode front_inner_back)
				(layer "Inner"
					(shape circle)
					(size 0.8001 0.8001)
					(clearance 0.1524)
				)
				(layer "B.Cu"
					(shape circle)
					(size 1.0033 1.0033)
					(thermal_gap 0.10795)
					(clearance 0.10795)
				)
			)
		)
	)
	(footprint ""
		(layer "B.Cu")
		(at 190.037212 -103.230426 90)
		(property "Reference" "R132"
			(at 0 0 90)
			(layer "B.SilkS")
			(hide yes)
			(effects
				(font
					(size 1.27 1.27)
				)
				(justify mirror)
			)
		)
		(property "Value" ""
			(at 0 0 90)
			(layer "B.Fab")
			(effects
				(font
					(size 1.27 1.27)
				)
				(justify mirror)
			)
		)
		(duplicate_pad_numbers_are_jumpers no)
		(fp_line
			(start 0.7874 -0.4064)
			(end -0.7874 -0.4064)
			(stroke
				(width 0.1524)
				(type default)
			)
			(layer "B.SilkS")
		)
		(fp_line
			(start -0.7874 -0.4064)
			(end -0.7874 0.4064)
			(stroke
				(width 0.1524)
				(type default)
			)
			(layer "B.SilkS")
		)
		(fp_line
			(start 0.7874 0.4064)
			(end 0.7874 -0.4064)
			(stroke
				(width 0.1524)
				(type default)
			)
			(layer "B.SilkS")
		)
		(fp_line
			(start -0.7874 0.4064)
			(end 0.7874 0.4064)
			(stroke
				(width 0.1524)
				(type default)
			)
			(layer "B.SilkS")
		)
		(fp_line
			(start 0.67945 -0.305054)
			(end 0.12065 -0.305054)
			(stroke
				(width 0.1)
				(type default)
			)
			(layer "B.Fab")
		)
		(fp_line
			(start 0.12065 -0.305054)
			(end 0.12065 -0.2794)
			(stroke
				(width 0.1)
				(type default)
			)
			(layer "B.Fab")
		)
		(fp_line
			(start -0.12065 -0.3048)
			(end -0.67945 -0.3048)
			(stroke
				(width 0.1)
				(type default)
			)
			(layer "B.Fab")
		)
		(fp_line
			(start -0.67945 -0.3048)
			(end -0.67945 0.3048)
			(stroke
				(width 0.1)
				(type default)
			)
			(layer "B.Fab")
		)
		(fp_line
			(start 0.12065 -0.2794)
			(end -0.12065 -0.2794)
			(stroke
				(width 0.1)
				(type default)
			)
			(layer "B.Fab")
		)
		(fp_line
			(start -0.12065 -0.2794)
			(end -0.12065 -0.3048)
			(stroke
				(width 0.1)
				(type default)
			)
			(layer "B.Fab")
		)
		(fp_line
			(start 0.12065 0.2794)
			(end 0.12065 0.3048)
			(stroke
				(width 0.1)
				(type default)
			)
			(layer "B.Fab")
		)
		(fp_line
			(start -0.120396 0.2794)
			(end 0.12065 0.2794)
			(stroke
				(width 0.1)
				(type default)
			)
			(layer "B.Fab")
		)
		(fp_line
			(start 0.67945 0.3048)
			(end 0.67945 -0.305054)
			(stroke
				(width 0.1)
				(type default)
			)
			(layer "B.Fab")
		)
		(fp_line
			(start 0.12065 0.3048)
			(end 0.67945 0.3048)
			(stroke
				(width 0.1)
				(type default)
			)
			(layer "B.Fab")
		)
		(fp_line
			(start -0.120396 0.3048)
			(end -0.120396 0.2794)
			(stroke
				(width 0.1)
				(type default)
			)
			(layer "B.Fab")
		)
		(fp_line
			(start -0.67945 0.3048)
			(end -0.120396 0.3048)
			(stroke
				(width 0.1)
				(type default)
			)
			(layer "B.Fab")
		)
		(pad "1" smd circle
			(at 0.40005 0 270)
			(size 0 0)
			(layers "B.Cu" "B.Mask" "B.Paste")
			(net "RST_CPU1_LVC1_R_N")
		)
		(pad "2" smd circle
			(at -0.40005 0 270)
			(size 0 0)
			(layers "B.Cu" "B.Mask" "B.Paste")
			(net "RST_CPU1_BUF_R_N")
		)
	)
)
